(kicad_pcb
	(version 20260206)
	(generator "pcbnew")
	(generator_version "10.0")
	(general
		(thickness 1.6)
		(legacy_teardrops no)
	)
	(paper "A4")
	(title_block
		(title "Bryce Canyon_IOM_M2_16342-2_OCP.brd")
		(comment 1 "Bryce Canyon / footprints 705-711 of 1146")
	)
	(layers
		(0 "F.Cu" signal "TOP")
		(4 "In1.Cu" signal "L2GND")
		(6 "In2.Cu" signal "L3")
		(8 "In3.Cu" signal "L4VCC")
		(10 "In4.Cu" signal "L5VCC")
		(12 "In5.Cu" signal "L6")
		(14 "In6.Cu" signal "L7GND")
		(2 "B.Cu" signal "BOTTOM")
		(9 "F.Adhes" user "F.Adhesive")
		(11 "B.Adhes" user "B.Adhesive")
		(13 "F.Paste" user "Package Geometry/Pastemask Top")
		(15 "B.Paste" user "Package Geometry/Pastemask Bottom")
		(5 "F.SilkS" user "Ref Des/Silkscreen Top")
		(7 "B.SilkS" user "Ref Des/Silkscreen Bottom")
		(1 "F.Mask" user "Board Geometry/Soldermask Top")
		(3 "B.Mask" user "Board Geometry/Soldermask Bottom")
		(17 "Dwgs.User" user "User.Drawings")
		(19 "Cmts.User" user "User.Comments")
		(21 "Eco1.User" user "User.Eco1")
		(23 "Eco2.User" user "User.Eco2")
		(25 "Edge.Cuts" user "Board Geometry/Outline")
		(27 "Margin" user)
		(31 "F.CrtYd" user "Package Geometry/Place Bound Top")
		(29 "B.CrtYd" user "Package Geometry/Place Bound Bottom")
		(35 "F.Fab" user "Ref Des/Assembly Top")
		(33 "B.Fab" user "Ref Des/Assembly Bottom")
	)
	(footprint ""
		(layer "F.Cu")
		(at 73.05548 -185.90768)
		(property "Reference" "R508"
			(at 0 0 0)
			(layer "F.SilkS")
			(hide yes)
			(effects
				(font
					(size 1.27 1.27)
				)
			)
		)
		(property "Value" "0R2J-2-GP"
			(at 0.064008 -3.993896 0)
			(unlocked yes)
			(layer "F.Fab")
			(hide yes)
			(effects
				(font
					(size 1.016 1.016)
					(thickness 0.1524)
				)
			)
		)
		(property "Device Type" "R402H16"
			(at 0.064008 -5.517896 0)
			(unlocked yes)
			(layer "F.Fab")
			(hide yes)
			(effects
				(font
					(size 1.016 1.016)
					(thickness 0.1524)
				)
			)
		)
		(duplicate_pad_numbers_are_jumpers no)
		(fp_line
			(start -0.508 -0.9398)
			(end -0.508 0.9398)
			(stroke
				(width 0.1524)
				(type default)
			)
			(layer "F.SilkS")
		)
		(fp_line
			(start 0.508 -0.9398)
			(end -0.508 -0.9398)
			(stroke
				(width 0.1524)
				(type default)
			)
			(layer "F.SilkS")
		)
		(fp_rect
			(start -0.508 0.9398)
			(end 0.508 -0.9398)
			(stroke
				(width 0)
				(type default)
			)
			(fill no)
			(layer "F.CrtYd")
		)
		(fp_rect
			(start -0.508 0.9398)
			(end 0.508 -0.9398)
			(stroke
				(width 0)
				(type default)
			)
			(fill no)
			(layer "F.Fab")
		)
		(pad "1" smd custom
			(at 0 -0.4445)
			(size 0.1397 0.1397)
			(layers "F.Cu" "F.Mask" "F.Paste")
			(net "P5V_STBY")
			(options
				(clearance outline)
				(anchor circle)
			)
			(primitives
				(gr_poly
					(pts
						(arc
							(start -0.1778 -0.2794)
							(mid -0.249642 -0.249642)
							(end -0.2794 -0.1778)
						)
						(arc
							(start -0.2794 0.1778)
							(mid -0.249642 0.249642)
							(end -0.1778 0.2794)
						)
						(arc
							(start 0.1778 0.2794)
							(mid 0.249642 0.249642)
							(end 0.2794 0.1778)
						)
						(arc
							(start 0.2794 -0.1778)
							(mid 0.249642 -0.249642)
							(end 0.1778 -0.2794)
						)
					)
					(width 0)
					(fill yes)
				)
			)
		)
		(pad "2" smd custom
			(at 0 0.4445)
			(size 0.1397 0.1397)
			(layers "F.Cu" "F.Mask" "F.Paste")
			(net "TPS74801_P2V5_STBY_BIAS")
			(options
				(clearance outline)
				(anchor circle)
			)
			(primitives
				(gr_poly
					(pts
						(arc
							(start -0.1778 -0.2794)
							(mid -0.249642 -0.249642)
							(end -0.2794 -0.1778)
						)
						(arc
							(start -0.2794 0.1778)
							(mid -0.249642 0.249642)
							(end -0.1778 0.2794)
						)
						(arc
							(start 0.1778 0.2794)
							(mid 0.249642 0.249642)
							(end 0.2794 0.1778)
						)
						(arc
							(start 0.2794 -0.1778)
							(mid 0.249642 -0.249642)
							(end 0.1778 -0.2794)
						)
					)
					(width 0)
					(fill yes)
				)
			)
		)
	)
	(footprint ""
		(layer "F.Cu")
		(at 63.17615 -160.979104 90)
		(property "Reference" "C96"
			(at 0 0 90)
			(layer "F.SilkS")
			(hide yes)
			(effects
				(font
					(size 1.27 1.27)
				)
			)
		)
		(property "Value" "SC100P50V2JN-3GP"
			(at 1.1811 -2.7051 90)
			(unlocked yes)
			(layer "F.Fab")
			(hide yes)
			(effects
				(font
					(size 1.016 1.016)
					(thickness 0.1524)
				)
			)
		)
		(property "Device Type" "C402H22"
			(at 1.1811 -4.2291 90)
			(unlocked yes)
			(layer "F.Fab")
			(hide yes)
			(effects
				(font
					(size 1.016 1.016)
					(thickness 0.1524)
				)
			)
		)
		(duplicate_pad_numbers_are_jumpers no)
		(fp_rect
			(start -0.4318 0.9525)
			(end 0.4318 -0.9525)
			(stroke
				(width 0)
				(type default)
			)
			(fill no)
			(layer "F.CrtYd")
		)
		(fp_rect
			(start -0.4318 0.9525)
			(end 0.4318 -0.9525)
			(stroke
				(width 0)
				(type default)
			)
			(fill no)
			(layer "F.Fab")
		)
		(pad "1" smd custom
			(at 0 -0.4445 90)
			(size 0.1524 0.1524)
			(layers "F.Cu" "F.Mask" "F.Paste")
			(net "VPLLAV33")
			(options
				(clearance outline)
				(anchor circle)
			)
			(primitives
				(gr_poly
					(pts
						(arc
							(start 0.3048 -0.2032)
							(mid 0.275042 -0.275042)
							(end 0.2032 -0.3048)
						)
						(arc
							(start -0.2032 -0.3048)
							(mid -0.275042 -0.275042)
							(end -0.3048 -0.2032)
						)
						(arc
							(start -0.3048 0.2032)
							(mid -0.275042 0.275042)
							(end -0.2032 0.3048)
						)
						(arc
							(start 0.2032 0.3048)
							(mid 0.275042 0.275042)
							(end 0.3048 0.2032)
						)
					)
					(width 0)
					(fill yes)
				)
			)
		)
		(pad "2" smd custom
			(at 0 0.4445 90)
			(size 0.1524 0.1524)
			(layers "F.Cu" "F.Mask" "F.Paste")
			(net "GND")
			(options
				(clearance outline)
				(anchor circle)
			)
			(primitives
				(gr_poly
					(pts
						(arc
							(start 0.3048 -0.2032)
							(mid 0.275042 -0.275042)
							(end 0.2032 -0.3048)
						)
						(arc
							(start -0.2032 -0.3048)
							(mid -0.275042 -0.275042)
							(end -0.3048 -0.2032)
						)
						(arc
							(start -0.3048 0.2032)
							(mid -0.275042 0.275042)
							(end -0.2032 0.3048)
						)
						(arc
							(start 0.2032 0.3048)
							(mid 0.275042 0.275042)
							(end 0.3048 0.2032)
						)
					)
					(width 0)
					(fill yes)
				)
			)
		)
	)
	(footprint ""
		(layer "F.Cu")
		(at 213.647528 -139.191238 45)
		(property "Reference" "VIA66"
			(at 0 0 45)
			(layer "F.SilkS")
			(hide yes)
			(effects
				(font
					(size 1.27 1.27)
				)
			)
		)
		(property "Value" "85OHM-8L-1D6MM-L16L18-GP"
			(at 4.064105 0.609655 45)
			(unlocked yes)
			(layer "F.Fab")
			(hide yes)
			(effects
				(font
					(size 1.016 1.016)
					(thickness 0.1524)
				)
			)
		)
		(property "Device Type" "VIA-PCIE-4P-368076"
			(at 4.064105 -0.914474 45)
			(unlocked yes)
			(layer "F.Fab")
			(hide yes)
			(effects
				(font
					(size 1.016 1.016)
					(thickness 0.1524)
				)
			)
		)
		(duplicate_pad_numbers_are_jumpers no)
		(fp_poly
			(pts
				(xy -1.841491 -0.381057) (xy 1.841509 -0.381058) (xy 1.841508 0.380942) (xy -1.841491 0.380942)
			)
			(stroke
				(width 0)
				(type default)
			)
			(fill no)
			(layer "F.CrtYd")
		)
		(fp_poly
			(pts
				(xy -1.841491 -0.381057) (xy 1.841509 -0.381058) (xy 1.841508 0.380942) (xy -1.841491 0.380942)
			)
			(stroke
				(width 0)
				(type default)
			)
			(fill no)
			(layer "F.Fab")
		)
		(pad "1" thru_hole circle
			(at -1.460499 0 45)
			(size 0.508 0.508)
			(drill 0.254)
			(layers "*.Cu" "*.Mask")
			(remove_unused_layers no)
			(net "GND")
			(clearance 0.127)
			(thermal_gap 0.127)
		)
		(pad "2" thru_hole circle
			(at -0.4445 0 45)
			(size 0.508 0.508)
			(drill 0.254)
			(layers "*.Cu" "*.Mask")
			(remove_unused_layers no)
			(net "PCIE_COMP_TO_IOM_CLK_2_DP")
			(clearance 0.127)
			(thermal_gap 0.127)
		)
		(pad "3" thru_hole circle
			(at 0.4445 0 45)
			(size 0.508 0.508)
			(drill 0.254)
			(layers "*.Cu" "*.Mask")
			(remove_unused_layers no)
			(net "PCIE_COMP_TO_IOM_CLK_2_DN")
			(clearance 0.127)
			(thermal_gap 0.127)
		)
		(pad "4" thru_hole circle
			(at 1.460499 0 45)
			(size 0.508 0.508)
			(drill 0.254)
			(layers "*.Cu" "*.Mask")
			(remove_unused_layers no)
			(net "GND")
			(clearance 0.127)
			(thermal_gap 0.127)
		)
	)
	(footprint ""
		(layer "F.Cu")
		(at 20.0787 -160.971484 180)
		(property "Reference" "R529"
			(at 0 0 180)
			(layer "F.SilkS")
			(hide yes)
			(effects
				(font
					(size 1.27 1.27)
				)
			)
		)
		(property "Value" "0R5J-5-GP"
			(at 0 -8.9535 180)
			(unlocked yes)
			(layer "F.Fab")
			(hide yes)
			(effects
				(font
					(size 1.27 1.016)
					(thickness 0.1524)
				)
			)
		)
		(property "Device Type" "R805H24"
			(at 0 -10.6299 180)
			(unlocked yes)
			(layer "F.Fab")
			(hide yes)
			(effects
				(font
					(size 1.27 1.016)
					(thickness 0.1524)
				)
			)
		)
		(duplicate_pad_numbers_are_jumpers no)
		(fp_line
			(start 0.889 1.7018)
			(end 0.889 -0.508)
			(stroke
				(width 0.1524)
				(type default)
			)
			(layer "F.SilkS")
		)
		(fp_line
			(start 0.889 -1.7018)
			(end 0.889 -0.381)
			(stroke
				(width 0.1524)
				(type default)
			)
			(layer "F.SilkS")
		)
		(fp_line
			(start 0.889 -1.7018)
			(end -0.889 -1.7018)
			(stroke
				(width 0.1524)
				(type default)
			)
			(layer "F.SilkS")
		)
		(fp_line
			(start -0.889 1.7018)
			(end 0.889 1.7018)
			(stroke
				(width 0.1524)
				(type default)
			)
			(layer "F.SilkS")
		)
		(fp_line
			(start -0.889 0.0762)
			(end -0.889 1.7018)
			(stroke
				(width 0.1524)
				(type default)
			)
			(layer "F.SilkS")
		)
		(fp_line
			(start -0.889 -1.7018)
			(end -0.889 0.2794)
			(stroke
				(width 0.1524)
				(type default)
			)
			(layer "F.SilkS")
		)
		(fp_poly
			(pts
				(xy 0.9652 -1.778) (xy 0.9652 1.778) (xy -0.9652 1.778) (xy -0.9652 -1.778)
			)
			(stroke
				(width 0)
				(type default)
			)
			(fill no)
			(layer "F.CrtYd")
		)
		(fp_rect
			(start -0.9652 1.778)
			(end 0.9652 -1.778)
			(stroke
				(width 0)
				(type default)
			)
			(fill no)
			(layer "F.Fab")
		)
		(pad "1" smd rect
			(at 0 -0.9652 180)
			(size 1.397 1.143)
			(layers "F.Cu" "F.Mask" "F.Paste")
			(net "P1V2_STBY")
		)
		(pad "2" smd rect
			(at 0 0.9652 180)
			(size 1.397 1.143)
			(layers "F.Cu" "F.Mask" "F.Paste")
			(net "TPS74801_P1V2_STBY_OUT")
		)
	)
	(footprint ""
		(layer "F.Cu")
		(at 35.394646 -174.67961 -90)
		(property "Reference" "R499"
			(at 0 0 270)
			(layer "F.SilkS")
			(hide yes)
			(effects
				(font
					(size 1.27 1.27)
				)
			)
		)
		(property "Value" "10KR2F-2-GP"
			(at 0.064008 -3.993896 270)
			(unlocked yes)
			(layer "F.Fab")
			(hide yes)
			(effects
				(font
					(size 1.016 1.016)
					(thickness 0.1524)
				)
			)
		)
		(property "Device Type" "R402H16"
			(at 0.064008 -5.517896 270)
			(unlocked yes)
			(layer "F.Fab")
			(hide yes)
			(effects
				(font
					(size 1.016 1.016)
					(thickness 0.1524)
				)
			)
		)
		(duplicate_pad_numbers_are_jumpers no)
		(fp_line
			(start -0.508 -0.9398)
			(end -0.508 0.9398)
			(stroke
				(width 0.1524)
				(type default)
			)
			(layer "F.SilkS")
		)
		(fp_line
			(start 0.508 -0.9398)
			(end -0.508 -0.9398)
			(stroke
				(width 0.1524)
				(type default)
			)
			(layer "F.SilkS")
		)
		(fp_rect
			(start -0.508 0.9398)
			(end 0.508 -0.9398)
			(stroke
				(width 0)
				(type default)
			)
			(fill no)
			(layer "F.CrtYd")
		)
		(fp_rect
			(start -0.508 0.9398)
			(end 0.508 -0.9398)
			(stroke
				(width 0)
				(type default)
			)
			(fill no)
			(layer "F.Fab")
		)
		(pad "1" smd custom
			(at 0 -0.4445 270)
			(size 0.1397 0.1397)
			(layers "F.Cu" "F.Mask" "F.Paste")
			(net "P3V3_STBY_VFB")
			(options
				(clearance outline)
				(anchor circle)
			)
			(primitives
				(gr_poly
					(pts
						(arc
							(start -0.1778 -0.2794)
							(mid -0.249642 -0.249642)
							(end -0.2794 -0.1778)
						)
						(arc
							(start -0.2794 0.1778)
							(mid -0.249642 0.249642)
							(end -0.1778 0.2794)
						)
						(arc
							(start 0.1778 0.2794)
							(mid 0.249642 0.249642)
							(end 0.2794 0.1778)
						)
						(arc
							(start 0.2794 -0.1778)
							(mid 0.249642 -0.249642)
							(end 0.1778 -0.2794)
						)
					)
					(width 0)
					(fill yes)
				)
			)
		)
		(pad "2" smd custom
			(at 0 0.4445 270)
			(size 0.1397 0.1397)
			(layers "F.Cu" "F.Mask" "F.Paste")
			(net "AGND_P3V3_STBY")
			(options
				(clearance outline)
				(anchor circle)
			)
			(primitives
				(gr_poly
					(pts
						(arc
							(start -0.1778 -0.2794)
							(mid -0.249642 -0.249642)
							(end -0.2794 -0.1778)
						)
						(arc
							(start -0.2794 0.1778)
							(mid -0.249642 0.249642)
							(end -0.1778 0.2794)
						)
						(arc
							(start 0.1778 0.2794)
							(mid 0.249642 0.249642)
							(end 0.2794 0.1778)
						)
						(arc
							(start 0.2794 -0.1778)
							(mid 0.249642 -0.249642)
							(end 0.1778 -0.2794)
						)
					)
					(width 0)
					(fill yes)
				)
			)
		)
	)
	(footprint ""
		(layer "F.Cu")
		(at 44.9072 -158.5976)
		(property "Reference" "R173"
			(at 0 0 0)
			(layer "F.SilkS")
			(hide yes)
			(effects
				(font
					(size 1.27 1.27)
				)
			)
		)
		(property "Value" "0R2J-2-GP"
			(at 0.064008 -3.993896 0)
			(unlocked yes)
			(layer "F.Fab")
			(hide yes)
			(effects
				(font
					(size 1.016 1.016)
					(thickness 0.1524)
				)
			)
		)
		(property "Device Type" "R402H16"
			(at 0.064008 -5.517896 0)
			(unlocked yes)
			(layer "F.Fab")
			(hide yes)
			(effects
				(font
					(size 1.016 1.016)
					(thickness 0.1524)
				)
			)
		)
		(duplicate_pad_numbers_are_jumpers no)
		(fp_line
			(start -0.508 -0.9398)
			(end -0.508 0.9398)
			(stroke
				(width 0.1524)
				(type default)
			)
			(layer "F.SilkS")
		)
		(fp_line
			(start 0.508 -0.9398)
			(end -0.508 -0.9398)
			(stroke
				(width 0.1524)
				(type default)
			)
			(layer "F.SilkS")
		)
		(fp_rect
			(start -0.508 0.9398)
			(end 0.508 -0.9398)
			(stroke
				(width 0)
				(type default)
			)
			(fill no)
			(layer "F.CrtYd")
		)
		(fp_rect
			(start -0.508 0.9398)
			(end 0.508 -0.9398)
			(stroke
				(width 0)
				(type default)
			)
			(fill no)
			(layer "F.Fab")
		)
		(pad "1" smd custom
			(at 0 -0.4445)
			(size 0.1397 0.1397)
			(layers "F.Cu" "F.Mask" "F.Paste")
			(net "I2C_M2_1_SCL")
			(options
				(clearance outline)
				(anchor circle)
			)
			(primitives
				(gr_poly
					(pts
						(arc
							(start -0.1778 -0.2794)
							(mid -0.249642 -0.249642)
							(end -0.2794 -0.1778)
						)
						(arc
							(start -0.2794 0.1778)
							(mid -0.249642 0.249642)
							(end -0.1778 0.2794)
						)
						(arc
							(start 0.1778 0.2794)
							(mid 0.249642 0.249642)
							(end 0.2794 0.1778)
						)
						(arc
							(start 0.2794 -0.1778)
							(mid 0.249642 -0.249642)
							(end 0.1778 -0.2794)
						)
					)
					(width 0)
					(fill yes)
				)
			)
		)
		(pad "2" smd custom
			(at 0 0.4445)
			(size 0.1397 0.1397)
			(layers "F.Cu" "F.Mask" "F.Paste")
			(net "BMC_SMB8_CLK")
			(options
				(clearance outline)
				(anchor circle)
			)
			(primitives
				(gr_poly
					(pts
						(arc
							(start -0.1778 -0.2794)
							(mid -0.249642 -0.249642)
							(end -0.2794 -0.1778)
						)
						(arc
							(start -0.2794 0.1778)
							(mid -0.249642 0.249642)
							(end -0.1778 0.2794)
						)
						(arc
							(start 0.1778 0.2794)
							(mid 0.249642 0.249642)
							(end 0.2794 0.1778)
						)
						(arc
							(start 0.2794 -0.1778)
							(mid 0.249642 -0.249642)
							(end 0.1778 -0.2794)
						)
					)
					(width 0)
					(fill yes)
				)
			)
		)
	)
	(footprint ""
		(layer "F.Cu")
		(at 28.2448 -180.7464)
		(property "Reference" "R495"
			(at 0 0 0)
			(layer "F.SilkS")
			(hide yes)
			(effects
				(font
					(size 1.27 1.27)
				)
			)
		)
		(property "Value" "866KR2F-GP"
			(at 0.064008 -3.993896 0)
			(unlocked yes)
			(layer "F.Fab")
			(hide yes)
			(effects
				(font
					(size 1.016 1.016)
					(thickness 0.1524)
				)
			)
		)
		(property "Device Type" "R402H16"
			(at 0.064008 -5.517896 0)
			(unlocked yes)
			(layer "F.Fab")
			(hide yes)
			(effects
				(font
					(size 1.016 1.016)
					(thickness 0.1524)
				)
			)
		)
		(duplicate_pad_numbers_are_jumpers no)
		(fp_line
			(start -0.508 -0.9398)
			(end -0.508 0.9398)
			(stroke
				(width 0.1524)
				(type default)
			)
			(layer "F.SilkS")
		)
		(fp_line
			(start 0.508 -0.9398)
			(end -0.508 -0.9398)
			(stroke
				(width 0.1524)
				(type default)
			)
			(layer "F.SilkS")
		)
		(fp_rect
			(start -0.508 0.9398)
			(end 0.508 -0.9398)
			(stroke
				(width 0)
				(type default)
			)
			(fill no)
			(layer "F.CrtYd")
		)
		(fp_rect
			(start -0.508 0.9398)
			(end 0.508 -0.9398)
			(stroke
				(width 0)
				(type default)
			)
			(fill no)
			(layer "F.Fab")
		)
		(pad "1" smd custom
			(at 0 -0.4445)
			(size 0.1397 0.1397)
			(layers "F.Cu" "F.Mask" "F.Paste")
			(net "P3V3_STBY_VREG")
			(options
				(clearance outline)
				(anchor circle)
			)
			(primitives
				(gr_poly
					(pts
						(arc
							(start -0.1778 -0.2794)
							(mid -0.249642 -0.249642)
							(end -0.2794 -0.1778)
						)
						(arc
							(start -0.2794 0.1778)
							(mid -0.249642 0.249642)
							(end -0.1778 0.2794)
						)
						(arc
							(start 0.1778 0.2794)
							(mid 0.249642 0.249642)
							(end 0.2794 0.1778)
						)
						(arc
							(start 0.2794 -0.1778)
							(mid 0.249642 -0.249642)
							(end 0.1778 -0.2794)
						)
					)
					(width 0)
					(fill yes)
				)
			)
		)
		(pad "2" smd custom
			(at 0 0.4445)
			(size 0.1397 0.1397)
			(layers "F.Cu" "F.Mask" "F.Paste")
			(net "P3V3_STBY_RF")
			(options
				(clearance outline)
				(anchor circle)
			)
			(primitives
				(gr_poly
					(pts
						(arc
							(start -0.1778 -0.2794)
							(mid -0.249642 -0.249642)
							(end -0.2794 -0.1778)
						)
						(arc
							(start -0.2794 0.1778)
							(mid -0.249642 0.249642)
							(end -0.1778 0.2794)
						)
						(arc
							(start 0.1778 0.2794)
							(mid 0.249642 0.249642)
							(end 0.2794 0.1778)
						)
						(arc
							(start 0.2794 -0.1778)
							(mid 0.249642 -0.249642)
							(end 0.1778 -0.2794)
						)
					)
					(width 0)
					(fill yes)
				)
			)
		)
	)
)
